# Barreleye-G2_Tri-mode BPX24-DVT-X01-SKU-BOM-X07-20171222_Final.xls.xlsx — SKU3 (bom)
| FOXCONN TECHNOLOGY GROUP |  |  |  |  |  |  |  |  |  |  |  |  |  |  |  |  |  |  |  |
| BILL OF MATERIAL |  |  |  |  |  |  |  |  |  |  |  |  |  |  |  |  |  |  |  |
| REV OF  BOM |  | CUSTOMER |  | <name> |  | CUSTOMER P/N |  | AA P/N：1A42NC500-600-2 | PWA DESCRIPTION |  |  |  | PRODUCT CODE |  |  | PWA  REV |  | DATE |  |
| Sourcing (Single/Sole/Multi) | Critical Commodity (Y or N) | Component Class (1, 2, other) | Customer PSL (Y or N) | Line Item | Item Number | Foxconn P/N | Customer P/N | Part Description | Manufacturer  Full Name | Manufacturer  Part Number | Qty | RoHS Status | Location | CC Qual Build: | Qual by (Customer / ODM ?) | The Date of Change Part or Add 2nd Source | Configuration Identifier | Customer Comments | ODM Comments |
|  |  |  |  | 1 | 1 | 0101FGA00-000-G |  | PCB,Zaius-Tri-mode BPX24 DVT-X01,OSP,Blu,22L,21.122*3.470,G | GOLD CIRCUIT ELECTRONICS LTD. | 0101FGA00-000-G | 1 | G | PCB |  |  |  |  |  |  |
|  |  |  |  |  | 1 | 0101FGA00-000-G |  | PCB,Zaius-Tri-mode BPX24 DVT-X01,OSP,Blu,22L,21.122*3.470,G | ZHUHAI FOUNDER PRINTED CIRCUIT BOARD（HK） DEVELOPMENT LIMITED | 0101FGA00-000-G |  | G |  |  |  |  |  |  |  |
|  |  |  |  | 2 | 2 | 62111H200-018-G |  | ECAP,680uF,+/-20%,16V,105_x0003_,G,SMD10X10.5,ESR<=80mOhm | RUBYCON CORP. | 16TZV680M10X10.5 | 1 | G | CE1 |  |  |  |  |  |  |
|  |  |  |  | 3 | 3 | 620101T02-015-G | - | CAP,100nF,+/-10%,X7R,16V,G,SMD0402 | MURATA ELEC. NORTH AMERICA | GRM155R71C104K | 145 | G | PSTC1,PFTC1,PETC1,C1,C2,C6,C8,C9,PSRC10,C10,C15,C19,C119,C123,C125,C129,C155,C159,C161,C165,C167,C171,C173,C177,C179,C183,C185,C189,C191,C192,C193,C194,C196,C198,C201,C207,C216,C217,C224,C249,C253,C255,C259,C261,C265,C267,C271,C273,C277,C279,C283,C285,C289,C291,C295,C297,C301,C303,C307,C309,C313,C315,C319,C321,C325,C327,C331,C333,C337,C339,C343,C397,C2101,C2102,C2103,C2104,C2105,C2106,C2107,C2108,C2109,C2110,C2111,C2112,C2113,C2114,C2115,C2116,C2117,C2118,C2119,C2120,C2121,C2122,C2123,C2124,C2125,C2126,C2127,C2128,C2129,C2130,C2131,C2132,C2133,C2134,C2135,C2136,C2137,C2138,C2139,C2140,C2141,C2143,C2145,C2147,C2149,C2169,C2171,C2176,C2177,C2178,C2232,C2233,C2234,C2235,C2237,C2239,C2240,C2241,C2242,C2254,C2255,C2256,C2259,C2260,C2261,C2262,C2263,C2264,C2265,C2266,C2270,C2271,C2272 |  |  |  |  |  |  |
|  |  |  |  |  | 3 | 620101T00-012-G |  | CAP,100nF,+/-10%,X7R,16V,G,SMD0402 | WALSIN TECHNOLOGY CORPORATION | 0402B104K160CT |  | G |  |  |  |  |  |  |  |
|  |  |  |  |  | 3 | 620101T00-026-G |  | CAP,100nF,+/-10%,X7R,16V,G,SMD0402 | SAMSUNG SEMICONDUCTOR | CL05B104KO5NNNC |  | G |  |  |  |  |  |  |  |
|  |  |  |  |  | 3 | 620101T00-015-G |  | CAP,100nF,+/-10%,X7R,16V,G,SMD0402 | MURATA ELEC. NORTH AMERICA | GRM155R71C104KA88D |  | G |  |  |  |  |  |  |  |
|  |  |  |  | 4 | 4 | 620100A00-015-G | - | CAP,10uF,+/-10%,X5R,16V,G,SMD1206 | MURATA ELEC. NORTH AMERICA | GRM31CR61C106K | 30 | G | C3,C4,C5,C7,C120,C128,C158,C164,C170,C176,C182,C188,C252,C258,C264,C270,C276,C282,C288,C294,C300,C306,C312,C318,C324,C330,C336,C342,C2236,C2238 |  |  |  |  |  |  |
|  |  |  |  |  | 4 | 620100A00-026-G |  | CAP,10uF,+/-10%,X5R,16V,G,SMD1206 | SAMSUNG SEMICONDUCTOR | CL31A106KOHNNNE |  | G |  |  |  |  |  |  |  |
|  |  |  |  |  | 4 | 620100A03-023-G |  | CAP,10uF,+/-10%,X5R,16V,G,SMD1206 | TAIYO ELECTRIC IND.CO.LTD | EMK316BJ106KL-T |  | G |  |  |  |  |  |  |  |
|  |  |  |  |  | 4 | 620100A00-012-G |  | CAP,10uF,+/-10%,X5R,16V,G,SMD1206 | WALSIN TECHNOLOGY CORPORATION | 1206X106K160CT |  | G |  |  |  |  |  |  |  |
|  |  |  |  |  | 4 | 620100A00-011-G |  | CAP,10uF,+/-10%,X5R,16V,G,SMD1206 | YAGEO CORPORATION COMPONENT | CC1206KKX5R7BB106 |  | G |  |  |  |  |  |  |  |
|  |  |  |  | 5 | 5 | 620117N00-015-G | - | CAP,22uF,+/-10%,X5R,16V,G,SMD1206 | MURATA ELEC. NORTH AMERICA | GRM31CR61C226K | 48 | G | C121,C122,C126,C130,C156,C160,C162,C166,C168,C172,C174,C178,C180,C184,C186,C190,C250,C254,C256,C260,C262,C266,C268,C272,C274,C278,C280,C284,C286,C290,C292,C296,C298,C302,C304,C308,C310,C314,C316,C320,C322,C326,C328,C332,C334,C338,C340,C344 |  |  |  |  |  |  |
|  |  |  |  |  | 5 | 620117N00-023-G |  | CAP,22uF,+/-10%,X5R,16V,G,SMD1206 | TAIYO ELECTRIC IND.CO.LTD | EMK316BJ226KL-T |  | G |  |  |  |  |  |  |  |
|  |  |  |  |  | 5 | 620117N01-026-G |  | CAP,22uF,+/-10%,X5R,16V,G,SMD1206 | SAMSUNG SEMICONDUCTOR | CL31A226KOHNNNE |  | G |  |  |  |  |  |  |  |
|  |  |  |  | 6 | 6 | 620108H00-015-G | - | CAP,22uF,+/-20%,X5R,6.3V,G,SMD0805 | MURATA ELEC. NORTH AMERICA | GRM21BR60J226M | 24 | G | C124,C127,C157,C163,C169,C175,C181,C187,C251,C257,C263,C269,C275,C281,C287,C293,C299,C305,C311,C317,C323,C329,C335,C341 |  |  |  |  |  |  |
|  |  |  |  |  | 6 | 620108H04-023-G |  | CAP,22uF,+/-20%,X5R,6.3V,G,SMD0805 | TAIYO ELECTRIC IND.CO.LTD | JMK212BJ226MG-T |  | G |  |  |  |  |  |  |  |
|  |  |  |  |  | 6 | 620108H00-026-G |  | CAP,22uF,+/-20%,X5R,6.3V,G,SMD0805 | SAMSUNG SEMICONDUCTOR | CL21A226MQQNNNE |  | G |  |  |  |  |  |  |  |
|  |  |  |  |  | 6 | 620108H00-011-G |  | CAP,22uF,+/-20%,X5R,6.3V,G,SMD0805 | YAGEO CORPORATION COMPONENT | CC0805MKX5R5BB226 |  | G |  |  |  |  |  |  |  |
|  |  |  |  | 7 | 7 | 62011AM00-015-G |  | CAP,6.8nF,+/-10%,X7R,50V,G,SMD0402 | MURATA ELEC. NORTH AMERICA | GRM155R71H682K | 1 | G | C195 |  |  |  |  |  |  |
|  |  |  |  |  | 7 | 62011AM00-012-G |  | CAP,6.8nF,+/-10%,X7R,50V,G,SMD0402 | WALSIN TECHNOLOGY CORPORATION | 0402B682K500CT |  | G |  |  |  |  |  |  |  |
|  |  |  |  |  | 7 | 62011AM00-026-G |  | CAP,6.8nF,+/-10%,X7R,50V,G,SMD0402 | SAMSUNG SEMICONDUCTOR | CL05B682KB5NNNC |  | G |  |  |  |  |  |  |  |
|  |  |  |  | 8 | 8 | 620105E00-015-G |  | CAP,1uF,+/-10%,X7R,10V,G,SMD0603 | MURATA ELEC. NORTH AMERICA | GRM188R71A105K | 2 | G | C197,C215 |  |  |  |  |  |  |
|  |  |  |  |  | 8 | 620105E00-012-G |  | CAP,1uF,+/-10%,X7R,10V,G,SMD0603 | WALSIN TECHNOLOGY CORPORATION | 0603B105K100CT |  | G |  |  |  |  |  |  |  |
|  |  |  |  |  | 8 | 620105E00-011-G |  | CAP,1uF,+/-10%,X7R,10V,G,SMD0603 | YAGEO CORPORATION COMPONENT | CC0603KRX7R6BB105 |  | G |  |  |  |  |  |  |  |
|  |  |  |  |  | 8 | 620105E00-026-G |  | CAP,1uF,+/-10%,X7R,10V,G,SMD0603 | SAMSUNG SEMICONDUCTOR | CL10B105KP8NNNC |  | G |  |  |  |  |  |  |  |
|  |  |  |  |  | 8 | 620105E01-023-G |  | CAP,1uF,+/-10%,X7R,10V,G,SMD0603 | TAIYO ELECTRIC IND.CO.LTD | LMK107B7105KA-T |  | G |  |  |  |  |  |  |  |
|  |  |  |  | 9 | 9 | 620103600-015-G | - | CAP,10nF,+/-10%,X7R,25V,G,SMD0402 | MURATA ELEC. NORTH AMERICA | GRM155R71E103K | 14 | G | C199,C202,C203,C204,C205,C218,C219,C220,C221,C222,C2243,C2244,C2251,C2252 |  |  |  |  |  |  |
|  |  |  |  |  | 9 | 620103600-012-G |  | CAP,10nF,+/-10%,X7R,25V,G,SMD0402 | WALSIN TECHNOLOGY CORPORATION | 0402B103K250CT |  | G |  |  |  |  |  |  |  |
|  |  |  |  |  | 9 | 620103600-011-G |  | CAP,10nF,+/-10%,X7R,25V,G,SMD0402 | YAGEO CORPORATION COMPONENT | CC0402KRX7R8BB103 |  | G |  |  |  |  |  |  |  |
|  |  |  |  |  | 9 | 620103600-026-G |  | CAP,10nF,+/-10%,X7R,25V,G,SMD0402 | SAMSUNG SEMICONDUCTOR | CL05B103KA5NNNC |  | G |  |  |  |  |  |  |  |
|  |  |  |  |  | 9 | 620103601-023-G |  | CAP,10nF,+/-10%,X7R,25V,G,SMD0402 | TAIYO ELECTRIC IND.CO.LTD | TMK105B7103KV-F |  | G |  |  |  |  |  |  |  |
|  |  |  |  | 10 | 10 | 62010L000-015-G | - | CAP,10uF,+/-20%,X5R,6.3V,G,SMD0603 | MURATA ELEC. NORTH AMERICA | GRM188R60J106M | 2 | G | C200,C214 |  |  |  |  |  |  |
|  |  |  |  |  | 10 | 62010L000-023-G |  | CAP,10uF,+/-20%,X5R,6.3V,G,SMD0603 | TAIYO ELECTRIC IND.CO.LTD | JMK107BJ106MA-T |  | G |  |  |  |  |  |  |  |
|  |  |  |  |  | 10 | 62010L000-012-G |  | CAP,10uF,+/-20%,X5R,6.3V,G,SMD0603 | WALSIN TECHNOLOGY CORPORATION | 0603X106M6R3CT |  | G |  |  |  |  |  |  |  |
|  |  |  |  |  | 10 | 62010L000-026-G |  | CAP,10uF,+/-20%,X5R,6.3V,G,SMD0603 | SAMSUNG SEMICONDUCTOR | CL10A106MQ8NNNC |  | G |  |  |  |  |  |  |  |
|  |  |  |  |  | 10 | 62010L000-011-G |  | CAP,10uF,+/-20%,X5R,6.3V,G,SMD0603 | YAGEO CORPORATION COMPONENT | CC0603MRX5R5BB106 |  | G |  |  |  |  |  |  |  |
|  |  |  |  | 11 | 11 | 62011NF01-015-G |  | CAP,2.2uF,+/-10%,X7R,25V,G,SMD0805 | MURATA ELEC. NORTH AMERICA | GRM21BR71E225K | 2 | G | C206,C223 |  |  |  |  |  |  |
|  |  |  |  |  | 11 | 62011NF00-026-G |  | CAP,2.2uF,+/-10%,X7R,25V,G,SMD0805 | SAMSUNG SEMICONDUCTOR | CL21B225KAFNNNE |  | G |  |  |  |  |  |  |  |
|  |  |  |  |  | 11 | 62011NF00-023-G |  | CAP,2.2uF,+/-10%,X7R,25V,G,SMD0805 | TAIYO ELECTRIC IND.CO.LTD | TMK212B7225KG-TR |  | G |  |  |  |  |  |  |  |
|  |  |  |  | 12 | 12 | 620114000-015-G |  | CAP,10uF,+/-10%,X5R,16V,G,SMD0805 | MURATA ELEC. NORTH AMERICA | GRM21BR61C106K | 3 | G | C1946,C2081,C2253 |  |  |  |  |  |  |
|  |  |  |  |  | 12 | 620114005-023-G |  | CAP,10uF,+/-10%,X5R,16V,G,SMD0805 | TAIYO ELECTRIC IND.CO.LTD | EMK212ABJ106KG-T |  | G |  |  |  |  |  |  |  |
|  |  |  |  |  | 12 | 620114000-026-G |  | CAP,10uF,+/-10%,X5R,16V,G,SMD0805 | SAMSUNG SEMICONDUCTOR | CL21A106KOQNNNE |  | G |  |  |  |  |  |  |  |
|  |  |  |  |  | 12 | 620114000-012-G |  | CAP,10uF,+/-10%,X5R,16V,G,SMD0805 | WALSIN TECHNOLOGY CORPORATION | 0805X106K160CT |  | G |  |  |  |  |  |  |  |
|  |  |  |  | 13 | 13 | 620105400-015-G |  | CAP,1uF,+/-10%,X7R,16V,G,SMD0603 | MURATA ELEC. NORTH AMERICA | GRM188R71C105K | 10 | G | C1950,C2080,C2245,C2246,C2247,C2248,C2249,C2250,C2257,C2258 |  |  |  |  |  |  |
|  |  |  |  |  | 13 | 620105400-012-G |  | CAP,1uF,+/-10%,X7R,16V,G,SMD0603 | WALSIN TECHNOLOGY CORPORATION | 0603B105K160CT |  | G |  |  |  |  |  |  |  |
|  |  |  |  |  | 13 | 620105400-011-G |  | CAP,1uF,+/-10%,X7R,16V,G,SMD0603 | YAGEO CORPORATION COMPONENT | CC0603KRX7R7BB105 |  | G |  |  |  |  |  |  |  |
|  |  |  |  |  | 13 | 620105400-026-G |  | CAP,1uF,+/-10%,X7R,16V,G,SMD0603 | SAMSUNG SEMICONDUCTOR | CL10B105KO8NNNC |  | G |  |  |  |  |  |  |  |
|  |  |  |  |  | 13 | 620105400-023-G |  | CAP,1uF,+/-10%,X7R,16V,G,SMD0603 | TAIYO ELECTRIC IND.CO.LTD | EMK107B7105KA-T |  | G |  |  |  |  |  |  |  |
|  |  |  |  | 14 | 14 | 62011LU00-015-G | - | CAP,100nF,+/-10%,X5R,16V,G,SMD0402 | MURATA ELEC. NORTH AMERICA | GRM155R61C104KA88D | 18 | G | C2198,C2208,C2209,C2210,C2211,C2212,C2213,C2214,C2215,C2216,C2217,C2218,C2219,C2220,C2221,C2222,C2223,C2224 |  |  |  |  |  |  |
|  |  |  |  |  | 14 | 620100300-023-G |  | CAP,100nF,+/-10%,X5R,16V,G,SMD0402 | TAIYO | EMK105BJ104KV-F |  | G |  |  |  |  |  |  |  |
|  |  |  |  |  | 14 | 620100300-026-G |  | CAP,100nF,+/-10%,X5R,16V,G,SMD0402 | SAMSUNG SEMICONDUCTOR | CL05A104KO5NNNC |  | G |  |  |  |  |  |  |  |
|  |  |  |  |  | 14 | 620100300-012-G |  | CAP,100nF,+/-10%,X5R,16V,G,SMD0402 | WALSIN TECHNOLOGY CORPORATION | 0402X104K160CT |  | G |  |  |  |  |  |  |  |
|  |  |  |  | 15 | 15 | 620109S00-023-G |  | CAP,4.7uF,+/-10%,X7R,10V,G,SMD0805 | TAIYO ELECTRIC IND.CO.LTD | LMK212B7475KG-T | 1 | G | C2231 |  |  |  |  |  |  |
|  |  |  |  |  | 15 | 620109S00-026-G |  | CAP,4.7uF,+/-10%,X7R,10V,G,SMD0805 | SAMSUNG SEMICONDUCTOR | CL21B475KPFNNNE |  | G |  |  |  |  |  |  |  |
|  |  |  |  |  | 15 | 620109S00-015-G |  | CAP,4.7uF,+/-10%,X7R,10V,G,SMD0805 | MURATA ELEC. NORTH AMERICA | GRM21BR71A475K |  | G |  |  |  |  |  |  |  |
|  |  |  |  | 16 | 16 | 62012UW00-015-G | - | CAP,6.8pF,+/-0.05pF,NPO(C0G),25V,G,SMD0402 | MURATA ELEC. NORTH AMERICA | GRM1555C1E6R8WA01D | 2 | G | C2268,C2269 |  |  |  |  |  |  |
|  |  |  |  |  | 16 | 62012UW00-012-G |  | CAP,6.8pF,+/-0.05pF,NPO(C0G),25V,G,SMD0402 | WALSIN TECHNOLOGY CORPORATION | 0402N6R8A250CT |  | G |  |  |  |  |  |  |  |
|  |  |  |  | 17 | 17 | 52110LN00-289-G |  | LED,Gre,LTST-C191KGKT,2.4V,30mA,G,SMD0603 | LITE-ON TECHNOLOGY CORPORATION | LTST-C191KGKT | 24 | G | LED37,LED39,LED49,LED51,LED53,LED55,LED57,LED59,LED61,LED63,LED65,LED67,LED69,LED71,LED73,LED75,LED77,LED79,LED81,LED83,LED85,LED87,LED89,LED91 |  |  |  |  |  |  |
|  |  |  |  | 18 | 18 | 52110A800-289-G | 6W731 | LED,Gre/Yel,LTST-C195KGJSKT,2.4V,30mA,G,SMD | LITE-ON TECHNOLOGY CORPORATION | LTST-C195KGJSKT | 24 | G | LED38,LED40,LED50,LED52,LED54,LED56,LED58,LED60,LED62,LED64,LED66,LED68,LED70,LED72,LED74,LED76,LED78,LED80,LED82,LED84,LED86,LED88,LED90,LED92 |  |  |  |  |  |  |
|  |  |  |  | 19 | 19 | 720101900-015-G | - | FB,60 Ohm@100MHz,+/-25%,3A,25mOhm,G,SMD0805 | MURATA ELEC. NORTH AMERICA | BLM21PG600SN1D | 1 | G | L1 |  |  |  |  |  |  |
|  |  |  |  | 20 | 20 | 72010JY00-015-G |  | FB,330 Ohm@100MHz,+/-25%,1.5A,70mOhm,G,SMD0603 | MURATA ELEC. NORTH AMERICA | BLM18SG331TN1D | 2 | G | L2,L4 |  |  |  |  |  |  |
|  |  |  |  | 21 | 21 | 72010WP00-059-G |  | FB,600 Ohm@100MHz,+/-25%,1.5A,150mOhm,G,SMD0603 | TAI-TECH Advanced Electronics Co., Ltd. | HCB1608KF-601T15 | 2 | G | L6,L28 |  |  |  |  |  |  |
|  |  |  |  | 22 | 22 | 720102001-015-G | - | FB,30 Ohm@100MHz,+/-25%,3A,15mOhm,G,SMD0805 | MURATA ELEC. NORTH AMERICA | BLM21PG300SN1D | 1 | G | L30 |  |  |  |  |  |  |
|  |  |  |  | 23 | 23 | 720101L00-074-G |  | FB,600Ohm@100MHz,+/-25%,200mA,500mOhm,SMD0603,G | CHILISIN ELECTRONICS CORP. | SBK160808T-601Y-N | 1 | G | L31 |  |  |  |  |  |  |
|  |  |  |  | 24 | 24 | 71020NS00-967-G |  | OSC,25MHz,+/-25ppm,3.3V,15pF,G,SMD | SaRonix-eCERA Corporation | FK2500025 | 2 | G | OSC1,OSC2 |  |  |  |  |  |  |
|  |  |  |  | 25 | 25 | 62120HT00-024-G |  | ECAP,SPEA,100uF,+/-20%,10V,105C,G,SMD2816,ESR<=40mOhm | PANASONIC INDUSTRIAL CO.,LTD. | EEFCX1A101R | 3 | G | PSTCE3003,PFTCE3003,PETCE3003 |  |  |  |  |  |  |
|  |  |  |  | 26 | 26 | 62012PT00-015-G |  | CAP,22uF,+/-20%,X6S,16V,G,SMD0805 | MURATA ELEC. NORTH AMERICA | GRM21BC81C226M | 14 | G | PSTC2,PFTC2,PETC2,PSTC3,PFTC3,PETC3,PSRC7,PSRC8,PSRC11,PSRC12,PSRC15,PSTC3000,PFTC3000,PETC3000 |  |  |  |  |  |  |
|  |  |  |  |  | 26 | 62012PT00-023-G |  | CAP,22uF,+/-20%,X6S,16V,G,SMD0805 | TAIYO ELECTRIC IND.CO.LTD | EDK212BC6226MG-T |  | G |  |  |  |  |  |  |  |
|  |  |  |  | 27 | 27 | 620108000-015-G | - | CAP,100pF,+/-5%,NPO(C0G),50V,G,SMD0402 | MURATA ELEC. NORTH AMERICA | GRM1555C1H101J | 3 | G | PSTC4,PFTC4,PETC4 |  |  |  |  |  |  |
|  |  |  |  |  | 27 | 62010800A-012-G |  | CAP,100pF,+/-5%,NPO(C0G),50V,G,SMD0402 | WALSIN TECHNOLOGY CORPORATION | 0402N101J500CT |  | G |  |  |  |  |  |  |  |
|  |  |  |  |  | 27 | 620108000-026-G |  | CAP,100pF,+/-5%,NPO(C0G),50V,G,SMD0402 | SAMSUNG SEMICONDUCTOR | CL05C101JB5NNNC |  | G |  |  |  |  |  |  |  |
|  |  |  |  |  | 27 | 620108000-023-G |  | CAP,100pF,+/-5%,NPO(C0G),50V,G,SMD0402 | TAIYO ELECTRIC IND.CO.LTD | UMK105CG101JV-F |  | G |  |  |  |  |  |  |  |
|  |  |  |  | 28 | 28 | 62010L800-015-G | - | CAP,1nF,+/-5%,NPO(C0G),50V,G,SMD0402 | MURATA ELEC. NORTH AMERICA | GRM1555C1H102J | 3 | G | PSTC5,PFTC5,PETC5 |  |  |  |  |  |  |
|  |  |  |  |  | 28 | 62010L800-012-G |  | CAP,1nF,+/-5%,NPO(C0G),50V,G,SMD0402 | WALSIN TECHNOLOGY CORPORATION | 0402N102J500CT |  | G |  |  |  |  |  |  |  |
|  |  |  |  |  | 28 | 62010L800-026-G |  | CAP,1nF,+/-5%,NPO(C0G),50V,G,SMD0402 | SAMSUNG SEMICONDUCTOR | CL05C102JB5NNNC |  | G |  |  |  |  |  |  |  |
|  |  |  |  | 29 | 29 | 62012T500-015-G |  | CAP,22uF,+/-20%,X7S,25V,G,SMD1206 | MURATA ELEC. NORTH AMERICA | GRM31CC71E226ME11L | 41 | G | PSRC2,PSTC6,PFTC6,PETC6,PSTC7,PFTC7,PETC7,PSTC8,PFTC8,PETC8,PSTC9,PFTC9,PETC9,PSRC17,PSTC3005,PFTC3005,PETC3005,PSTC3006,PFTC3006,PETC3006,PSTC3007,PFTC3007,PETC3007,PSTC3010,PFTC3010,PETC3010,PSTC3011,PFTC3011,PETC3011,PSTC3012,PFTC3012,PETC3012,PSTC3013,PFTC3013,PETC3013,PFTC3014,PETC3014,PFTC3015,PETC3015,PFTC3016,PETC3016 |  |  |  |  |  |  |
|  |  |  |  | 30 | 30 | 620103U00-015-G | - | CAP,470pF,+/-10%,X7R,50V,G,SMD0402 | MURATA ELEC. NORTH AMERICA | GRM155R71H471K | 3 | G | PSTC10,PFTC10,PETC10 |  |  |  |  |  |  |
|  |  |  |  |  | 30 | 620103U00-012-G |  | CAP,470pF,+/-10%,X7R,50V,G,SMD0402 | WALSIN TECHNOLOGY CORPORATION | 0402B471K500CT |  | G |  |  |  |  |  |  |  |
|  |  |  |  |  | 30 | 620103U00-026-G |  | CAP,470pF,+/-10%,X7R,50V,G,SMD0402 | SAMSUNG SEMICONDUCTOR | CL05B471KB5NNNC |  | G |  |  |  |  |  |  |  |
|  |  |  |  |  | 30 | 620103U00-023-G |  | CAP,470pF,+/-10%,X7R,50V,G,SMD0402 | TAIYO ELECTRIC IND.CO.LTD | UMK105B7471KV-F |  | G |  |  |  |  |  |  |  |
|  |  |  |  | 31 | 31 | 62010FG00-015-G | - | CAP,3.3pF,+/-0.25pF,NPO(C0G),50V,G,SMD0402 | MURATA ELEC. NORTH AMERICA | GRM1555C1H3R3C | 3 | G | PSTC11,PFTC11,PETC11 |  |  |  |  |  |  |
|  |  |  |  |  | 31 | 62010FG08-012-G |  | CAP,3.3pF,+/-0.25pF,NPO(C0G),50V,G,SMD0402 | WALSIN TECHNOLOGY CORPORATION | 0402N3R3C500CT |  | G |  |  |  |  |  |  |  |
|  |  |  |  |  | 31 | 62010FG00-026-G |  | CAP,3.3pF,+/-0.25pF,NPO(C0G),50V,G,SMD0402 | SAMSUNG SEMICONDUCTOR | CL05C3R3CB5ANNC |  | G |  |  |  |  |  |  |  |
|  |  |  |  | 32 | 32 | 620107L00-015-G | - | CAP,2.2nF,+/-10%,X7R,50V,G,SMD0402 | MURATA ELEC. NORTH AMERICA | GRM155R71H222K | 3 | G | PSTC12,PFTC12,PETC12 |  |  |  |  |  |  |
|  |  |  |  |  | 32 | 620107L00-012-G |  | CAP,2.2nF,+/-10%,X7R,50V,G,SMD0402 | WALSIN TECHNOLOGY CORPORATION | 0402B222K500CT |  | G |  |  |  |  |  |  |  |
|  |  |  |  |  | 32 | 620107L00-026-G |  | CAP,2.2nF,+/-10%,X7R,50V,G,SMD0402 | SAMSUNG SEMICONDUCTOR | CL05B222KB5NNNC |  | G |  |  |  |  |  |  |  |
|  |  |  |  |  | 32 | 620107L03-023-G |  | CAP,2.2nF,+/-10%,X7R,50V,G,SMD0402 | TAIYO ELECTRIC IND.CO.LTD | UMK105B7222KV-F |  | G |  |  |  |  |  |  |  |
|  |  |  |  | 33 | 33 | 62012A400-015-G | - | CAP,100nF,+/-10%,X7R,25V,G,SMD0402 | MURATA ELEC. NORTH AMERICA | GRM155R71E104KE14D | 8 | G | PSRC1,PSRC6,PSTC3002,PFTC3002,PETC3002,PSTC3008,PFTC3008,PETC3008 |  |  |  |  |  |  |
|  |  |  |  |  | 33 | 62012A400-023-G |  | CAP,100nF,+/-10%,X7R,25V,G,SMD0402 | TAIYO ELECTRIC IND.CO.LTD | TMK105B7104KV-FR |  | G |  |  |  |  |  |  |  |
|  |  |  |  |  | 33 | 62012A400-026-G |  | CAP,100nF,+/-10%,X7R,25V,G,SMD0402 | SAMSUNG SEMICONDUCTOR | CL05B104KA5NNNC |  | G |  |  |  |  |  |  |  |
|  |  |  |  |  | 33 | 62012A400-012-G |  | CAP,100nF,+/-10%,X7R,25V,G,SMD0402 | WALSIN TECHNOLOGY CORPORATION | 0402B104K250CT |  | G |  |  |  |  |  |  |  |
|  |  |  |  | 34 | 34 | 62012T300-015-G |  | CAP,1uF,+/-10%,X7S,25V,G,SMD0402 | MURATA ELEC. NORTH AMERICA | GRM155C71E105KE11D | 4 | G | PSRC4,PSTC3003,PFTC3003,PETC3003 |  |  |  |  |  |  |
|  |  |  |  |  | 34 | 620138700-026-G |  | CAP,1uF,+/-10%,X6S,25V,G,SMD0402 | SAMSUNG SEMICONDUCTOR | CL05X105KA5NQNC |  | G |  |  |  |  |  |  |  |
|  |  |  |  |  | 34 | 620138700-015-G |  | CAP,1uF,+/-10%,X6S,25V,G,SMD0402 | MURATA | GRM155C81E105KE11D |  | G |  |  |  |  |  |  |  |
|  |  |  |  | 35 | 35 | 62012GG00-015-G |  | CAP,10uF,+/-10%,X7S,25V,G,SMD0805 | MURATA ELEC. NORTH AMERICA | GRM21BC71E106K | 7 | G | PSRC3,PSTC3004,PFTC3004,PETC3004,PSTC3009,PFTC3009,PETC3009 |  |  |  |  |  |  |
|  |  |  |  |  | 35 | 62012GG00-012-G |  | CAP,10uF,+/-10%,X7S,25V,G,SMD0805 | WALSIN TECHNOLOGY CORPORATION | 0805A106K250CT |  | G |  |  |  |  |  |  |  |
|  |  |  |  | 36 | 36 | 63032RP05-129-G |  | IND,820nH@100KHz,+/-20%,13A,8mOhm,SHLD,G,SMD | MAG.LAYERS, SCIENTIFIC-TECHNICS (KUNSHAN) CO., LTD. | SPS-06CZ-R82M-V1 | 3 | G | PSTL1,PFTL1,PETL1 |  |  |  |  |  |  |
|  |  |  |  | 37 | 37 | 630341400-088-G |  | IND,22nH@1MHz,+/-20%,19A,368uOhm,SHLD,G,SMD | COOPER BUSSMANN, INC. | FP0404R1-R022-R | 3 | G | PSTL2,PFTL2,PETL2 |  |  |  |  |  |  |
|  |  |  |  | 38 | 38 | 61010LA00-017-G | - | RES,4.7KOhm,+/-1%,1/16W,G,SMD0402 | KOA SPEER ELECTRONICS, INC. | RK73H1ETTP4701F | 45 | G | PSTR1,PFTR1,PETR1,R336,R1605,R1700,R1701,R1702,R1703,R1704,R1705,R1706,R1707,R1708,R1709,R1710,R1711,R1712,R1713,R1714,R1715,R1716,R1717,R1718,R1719,R1720,R1721,R1722,R1723,R1724,R1725,R1726,R1727,R1728,R1729,R1730,R1731,R1732,R1733,R1734,R1735,R1736,R1737,R1738,R1739 |  |  |  |  |  |  |
|  |  |  |  |  | 38 | 61010LA00-012-G |  | RES,4.7KOhm,+/-1%,1/16W,G,SMD0402 | WALSIN TECHNOLOGY CORPORATION | WR04X4701FTL |  | G |  |  |  |  |  |  |  |
|  |  |  |  |  | 38 | 61010LA00-011-G |  | RES,4.7KOhm,+/-1%,1/16W,G,SMD0402 | YAGEO CORPORATION COMPONENT | RC0402FR-074K7L |  | G |  |  |  |  |  |  |  |
|  |  |  |  |  | 38 | 61010LA00-044-G |  | RES,4.7KOhm,+/-1%,1/16W,G,SMD0402 | TA-I TECHNOLOGY CO., LTD | RM04FTN4701 |  | G |  |  |  |  |  |  |  |
|  |  |  |  | 39 | 39 | 610107A00-017-G | - | RES,0 Ohm,+/-5%,1/16W,G,SMD0402 | KOA SPEER ELECTRONICS, INC. | RK73Z1ETTP | 146 | G | PSTR2,PFTR2,PETR2,R5,PSTR7,PFTR7,PETR7,R8,PSTR8,PSRR8,PFTR8,PETR8,PSRR9,R10,PSTR14,PFTR14,PETR14,PSRR15,PSRR18,PSTR22,PSRR22,PFTR22,PETR22,R60,R65,R511,R568,R569,R570,R571,R1888,R1889,R1890,R1891,R1892,R1893,R1894,R1895,R1896,R1897,R1898,R1899,R1900,R1901,R1902,R1903,R1988,R1989,R1990,R1991,R1992,R1993,R1994,R1995,R1996,R1997,R1998,R1999,R2000,R2001,R2002,R2003,R2004,R2005,R2006,R2007,R2008,R2009,R2010,R2011,R2012,R2013,R2014,R2015,R2016,R2017,R2018,R2019,R2020,R2021,R2022,R2023,R2024,R2025,R2026,R2027,R2028,R2029,R2030,R2031,R2032,R2033,R2034,R2035,R2036,R2037,R2038,R2039,R2040,R2041,R2042,R2043,R2044,R2045,R2046,R2047,R2061,R2066,R2067,R2070,R2085,R2086,R2152,R2153,R2154,R2155,R2158,R2180,R2181,R2182,R2183,R2184,R2185,R2186,R2187,R2188,R2189,R2190,R2191,R2192,R2193,R2194,R2195,R2196,R2197,R2198,R2199,PSTR3001,PFTR3001,PETR3001,PSTR3002,PFTR3002,PETR3002,PSTR3003,PFTR3003,PETR3003 |  |  |  |  |  |  |
|  |  |  |  |  | 39 | 610107A00-012-G |  | RES,0 Ohm,+/-5%,1/16W,G,SMD0402 | WALSIN TECHNOLOGY CORPORATION | WR04X000PTL |  | G |  |  |  |  |  |  |  |
|  |  |  |  |  | 39 | 610107A00-011-G |  | RES,0 Ohm,+/-5%,1/16W,G,SMD0402 | YAGEO CORPORATION COMPONENT | RC0402JR-070RL |  | G |  |  |  |  |  |  |  |
|  |  |  |  |  | 39 | 610107A00-044-G |  | RES,0 Ohm,+/-5%,1/16W,G,SMD0402 | TA-I TECHNOLOGY CO., LTD | RM04JTN0 |  | G |  |  |  |  |  |  |  |
|  |  |  |  |  | 39 | 610107A00-024-G |  | RES,0 Ohm,+/-5%,1/16W,G,SMD0402 | PANASONIC INDUSTRIAL CO.,LTD. | ERJ2GE0R00X |  | G |  |  |  |  |  |  |  |
|  |  |  |  |  | 39 | 610107A00-029-G |  | RES,0 Ohm,+/-5%,1/16W,G,SMD0402 | VISHAY ENTER TECHNO LOGY.INC | CRCW04020000Z0ED |  | G |  |  |  |  |  |  |  |
|  |  |  |  | 40 | 40 | 61011HA00-017-G |  | RES,1 Ohm,+/-1%,1/16W,G,SMD0402 | KOA SPEER ELECTRONICS, INC. | RK73H1ETTP1R00F | 4 | G | PSTR4,PFTR4,PETR4,PSRR5 |  |  |  |  |  |  |
|  |  |  |  |  | 40 | 61011HA00-012-G |  | RES,1 Ohm,+/-1%,1/16W,G,SMD0402 | WALSIN TECHNOLOGY CORPORATION | WR04W1R00FTL |  | G |  |  |  |  |  |  |  |
|  |  |  |  |  | 40 | 61011HA00-011-G |  | RES,1 Ohm,+/-1%,1/16W,G,SMD0402 | YAGEO CORPORATION COMPONENT | RC0402FR-071RL |  | G |  |  |  |  |  |  |  |
|  |  |  |  |  | 40 | 61011HA00-044-G |  | RES,1 Ohm,+/-1%,1/16W,G,SMD0402 | TA-I TECHNOLOGY CO., LTD | RM04FTN1R00 |  | G |  |  |  |  |  |  |  |
|  |  |  |  |  | 40 | 61011HA00-029-G |  | RES,1 Ohm,+/-1%,1/16W,G,SMD0402 | VISHAY ENTER TECHNO LOGY.INC | CRCW04021R00FNED |  | G |  |  |  |  |  |  |  |
|  |  |  |  | 41 | 41 | 61100QD00-044-G |  | RES,787 Ohm,+/-0.1%,1/16W,G,SMD0402 | TA-I TECHNOLOGY CO., LTD | RB04BTP7870 | 3 | G | PSTR5,PFTR5,PETR5 |  |  |  |  |  |  |
|  |  |  |  | 42 | 42 | 61100SU00-044-G |  | RES,105 Ohm,+/-0.1%,1/16W,G,SMD0402 | TA-I TECHNOLOGY CO., LTD | RB04BTP1050 | 3 | G | PSTR6,PFTR6,PETR6 |  |  |  |  |  |  |
|  |  |  |  | 43 | 43 | 61011BD00-017-G |  | RES,46.4KOhm,+/-1%,1/16W,G,SMD0402 | KOA SPEER ELECTRONICS, INC. | RK73H1ETTP4642F | 3 | G | PSTR9,PFTR9,PETR9 |  |  |  |  |  |  |
|  |  |  |  |  | 43 | 61011BD00-011-G |  | RES,46.4KOhm,+/-1%,1/16W,G,SMD0402 | YAGEO CORPORATION COMPONENT | RC0402FR-0746K4L |  | G |  |  |  |  |  |  |  |
|  |  |  |  |  | 43 | 61011BD00-012-G |  | RES,46.4KOhm,+/-1%,1/16W,G,SMD0402 | WALSIN TECHNOLOGY CORPORATION | WR04X4642FTL |  | G |  |  |  |  |  |  |  |
|  |  |  |  |  | 43 | 61011BD00-044-G |  | RES,46.4KOhm,+/-1%,1/16W,G,SMD0402 | TA-I TECHNOLOGY CO., LTD | RM04FTN4642 |  | G |  |  |  |  |  |  |  |
|  |  |  |  | 44 | 44 | 610124U00-017-G | - | RES,7.87KOhm,+/-1%,1/16W,G,SMD0402 | KOA SPEER ELECTRONICS, INC. | RK73H1ETTP7871F | 3 | G | PSTR10,PFTR10,PETR10 |  |  |  |  |  |  |
|  |  |  |  |  | 44 | 610124U00-012-G |  | RES,7.87KOhm,+/-1%,1/16W,G,SMD0402 | WALSIN TECHNOLOGY CORPORATION | WR04X7871FTL |  | G |  |  |  |  |  |  |  |
|  |  |  |  |  | 44 | 610124U00-011-G |  | RES,7.87KOhm,+/-1%,1/16W,G,SMD0402 | YAGEO CORPORATION COMPONENT | RC0402FR-077K87L |  | G |  |  |  |  |  |  |  |
|  |  |  |  |  | 44 | 610124U00-044-G |  | RES,7.87KOhm,+/-1%,1/16W,G,SMD0402 | TA-I TECHNOLOGY CO., LTD | RM04FTN7871 |  | G |  |  |  |  |  |  |  |
|  |  |  |  | 45 | 45 | 610112J00-017-G | - | RES,200 Ohm,+/-1%,1/16W,G,SMD0402 | KOA SPEER ELECTRONICS, INC. | RK73H1ETTP2000F | 3 | G | PSTR11,PFTR11,PETR11 |  |  |  |  |  |  |
|  |  |  |  |  | 45 | 610112J00-012-G |  | RES,200 Ohm,+/-1%,1/16W,G,SMD0402 | WALSIN TECHNOLOGY CORPORATION | WR04X2000FTL |  | G |  |  |  |  |  |  |  |
|  |  |  |  |  | 45 | 610112J00-011-G |  | RES,200 Ohm,+/-1%,1/16W,G,SMD0402 | YAGEO CORPORATION COMPONENT | RC0402FR-07200RL |  | G |  |  |  |  |  |  |  |
|  |  |  |  |  | 45 | 610112J00-044-G |  | RES,200 Ohm,+/-1%,1/16W,G,SMD0402 | TA-I TECHNOLOGY CO., LTD | RM04FTN2000 |  | G |  |  |  |  |  |  |  |
|  |  |  |  |  | 45 | 610112J00-029-G |  | RES,200 Ohm,+/-1%,1/16W,G,SMD0402 | VISHAY ENTER TECHNO LOGY.INC | CRCW0402200RFKED |  | G |  |  |  |  |  |  |  |
|  |  |  |  |  | 45 | 610112J00-024-G |  | RES,200 Ohm,+/-1%,1/16W,G,SMD0402 | PANASONIC INDUSTRIAL CO.,LTD. | ERJ2RKF2000X |  | G |  |  |  |  |  |  |  |
|  |  |  |  | 46 | 46 | 61011JY00-017-G | - | RES,39.2KOhm,+/-1%,1/16W,G,SMD0402 | KOA SPEER ELECTRONICS, INC. | RK73H1ETTP3922F | 3 | G | PSTR15,PFTR15,PETR15 |  |  |  |  |  |  |
|  |  |  |  |  | 46 | 61011JY00-012-G |  | RES,39.2KOhm,+/-1%,1/16W,G,SMD0402 | WALSIN TECHNOLOGY CORPORATION | WR04X3922FTL |  | G |  |  |  |  |  |  |  |
|  |  |  |  |  | 46 | 61011JY00-011-G |  | RES,39.2KOhm,+/-1%,1/16W,G,SMD0402 | YAGEO CORPORATION COMPONENT | RC0402FR-0739K2L |  | G |  |  |  |  |  |  |  |
|  |  |  |  |  | 46 | 61011JY00-044-G |  | RES,39.2KOhm,+/-1%,1/16W,G,SMD0402 | TA-I TECHNOLOGY CO., LTD | RM04FTN3922 |  | G |  |  |  |  |  |  |  |
|  |  |  |  |  | 46 | 61011JY00-029-G |  | RES,39.2KOhm,+/-1%,1/16W,G,SMD0402 | VISHAY ENTER TECHNO LOGY.INC | CRCW040239K2FKED |  | G |  |  |  |  |  |  |  |
|  |  |  |  | 47 | 47 | 32013P700-238-G |  | IC,Regulator,IR3448MTRPBF,ADJ,16A,G,PQFN-33,SMD | INTERNATIONAL RECTIFIER | IR3448MTRPBF | 3 | G | PSTU1,PFTU1,PETU1 |  |  |  |  |  |  |
|  |  |  |  | 48 | 48 | 62012P100-015-G |  | CAP,2.2uF,+/-20%,X7S,10V,G,SMD0402 | MURATA ELEC. NORTH AMERICA | GRM155C71A225M | 1 | G | PSRC5 |  |  |  |  |  |  |
|  |  |  |  |  | 48 | 62012P100-012-G |  | CAP,2.2uF,+/-20%,X7S,10V,G,SMD0402 | WALSIN TECHNOLOGY CORPORATION | 0402A225M100CT |  | G |  |  |  |  |  |  |  |
|  |  |  |  | 49 | 49 | 620105U00-015-G | - | CAP,220pF,+/-10%,X7R,50V,G,SMD0402 | MURATA ELEC. NORTH AMERICA | GRM155R71H221K | 1 | G | PSRC14 |  |  |  |  |  |  |
|  |  |  |  |  | 49 | 620105U00-012-G |  | CAP,220pF,+/-10%,X7R,50V,G,SMD0402 | WALSIN TECHNOLOGY CORPORATION | 0402B221K500CT |  | G |  |  |  |  |  |  |  |
|  |  |  |  |  | 49 | 620105U00-026-G |  | CAP,220pF,+/-10%,X7R,50V,G,SMD0402 | SAMSUNG SEMICONDUCTOR | CL05B221KB5NNNC |  | G |  |  |  |  |  |  |  |
|  |  |  |  | 50 | 50 | 62012H100-015-G |  | CAP,10uF,+/-20%,X6S,10V,G,SMD0603 | MURATA ELEC. NORTH AMERICA | GRM188C81A106M | 1 | G | PSRC16 |  |  |  |  |  |  |
|  |  |  |  |  | 50 | 62012H100-023-G |  | CAP,10uF,+/-20%,X6S,10V,G,SMD0603 | TAIYO ELECTRIC IND.CO.LTD | LMK107BC6106MA-T |  | G |  |  |  |  |  |  |  |
|  |  |  |  |  | 50 | 62012H100-026-G |  | CAP,10uF,+/-20%,X6S,10V,G,SMD0603 | SAMSUNG SEMICONDUCTOR | CL10X106MP8NRNC |  | G |  |  |  |  |  |  |  |
|  |  |  |  | 51 | 51 | 72010RE00-015-G |  | FB,26 Ohm@100MHz,+/-25%,6A,7mOhm,G,SMD0603 | MURATA ELEC. NORTH AMERICA | BLM18KG260TN1D | 1 | G | PSRL1 |  |  |  |  |  |  |
|  |  |  |  | 52 | 52 | 63031AD04-129-G |  | IND,4.7uH@100KHz,+/-20%,5.5A,40mOhm,SHLD,G,SMD | MAG.LAYERS, SCIENTIFIC-TECHNICS (KUNSHAN) CO., LTD. | SPS-06CZ-4R7M-V1 | 1 | G | PSRL2 |  |  |  |  |  |  |
|  |  |  |  | 53 | 53 | 610117D00-017-G | - | RES,13.3KOhm,+/-1%,1/16W,G,SMD0402 | KOA SPEER ELECTRONICS, INC. | RK73H1ETTP1332F | 1 | G | PSRR1 |  |  |  |  |  |  |
|  |  |  |  |  | 53 | 610117D00-012-G |  | RES,13.3KOhm,+/-1%,1/16W,G,SMD0402 | WALSIN TECHNOLOGY CORPORATION | WR04X1332FTL |  | G |  |  |  |  |  |  |  |
|  |  |  |  |  | 53 | 610117D00-011-G |  | RES,13.3KOhm,+/-1%,1/16W,G,SMD0402 | YAGEO CORPORATION COMPONENT | RC0402FR-0713K3L |  | G |  |  |  |  |  |  |  |
|  |  |  |  |  | 53 | 610117D00-044-G |  | RES,13.3KOhm,+/-1%,1/16W,G,SMD0402 | TA-I TECHNOLOGY CO., LTD | RM04FTN1332 |  | G |  |  |  |  |  |  |  |
|  |  |  |  | 54 | 54 | 610114S00-017-G | - | RES,4.99KOhm,+/-1%,1/16W,G,SMD0402 | KOA SPEER ELECTRONICS, INC. | RK73H1ETTP4991F | 1 | G | PSRR3 |  |  |  |  |  |  |
|  |  |  |  |  | 54 | 610114S00-012-G |  | RES,4.99KOhm,+/-1%,1/16W,G,SMD0402 | WALSIN TECHNOLOGY CORPORATION | WR04X4991FTL |  | G |  |  |  |  |  |  |  |
|  |  |  |  |  | 54 | 610114S00-011-G |  | RES,4.99KOhm,+/-1%,1/16W,G,SMD0402 | YAGEO CORPORATION COMPONENT | RC0402FR-074K99L |  | G |  |  |  |  |  |  |  |
|  |  |  |  |  | 54 | 610114S00-044-G |  | RES,4.99KOhm,+/-1%,1/16W,G,SMD0402 | TA-I TECHNOLOGY CO., LTD | RM04FTN4991 |  | G |  |  |  |  |  |  |  |
|  |  |  |  |  | 54 | 610114S00-024-G |  | RES,4.99KOhm,+/-1%,1/16W,G,SMD0402 | PANASONIC INDUSTRIAL CO.,LTD. | ERJ2RKF4991X |  | G |  |  |  |  |  |  |  |
|  |  |  |  | 55 | 55 | 61010G500-017-G | - | RES,10KOhm,+/-1%,1/16W,G,SMD0402 | KOA SPEER ELECTRONICS, INC. | RK73H1ETTP1002F | 1 | G | PSRR6 |  |  |  |  |  |  |
|  |  |  |  |  | 55 | 61010G500-012-G |  | RES,10KOhm,+/-1%,1/16W,G,SMD0402 | WALSIN TECHNOLOGY CORPORATION | WR04X1002FTL |  | G |  |  |  |  |  |  |  |
|  |  |  |  |  | 55 | 61010G500-011-G |  | RES,10KOhm,+/-1%,1/16W,G,SMD0402 | YAGEO CORPORATION COMPONENT | RC0402FR-0710KL |  | G |  |  |  |  |  |  |  |
|  |  |  |  |  | 55 | 61010G500-044-G |  | RES,10KOhm,+/-1%,1/16W,G,SMD0402 | TA-I TECHNOLOGY CO., LTD | RM04FTN1002 |  | G |  |  |  |  |  |  |  |
|  |  |  |  |  | 55 | 61010G500-029-G |  | RES,10KOhm,+/-1%,1/16W,G,SMD0402 | VISHAY ENTER TECHNO LOGY.INC | CRCW040210K0FKED |  | G |  |  |  |  |  |  |  |
|  |  |  |  |  | 55 | 61010G500-024-G |  | RES,10KOhm,+/-1%,1/16W,G,SMD0402 | PANASONIC INDUSTRIAL CO.,LTD. | ERJ2RKF1002X |  | G |  |  |  |  |  |  |  |
|  |  |  |  | 56 | 56 | 611004M00-017-G |  | RES,16.5KOhm,+/-0.1%,1/16W,G,SMD0402 | KOA SPEER ELECTRONICS, INC. | RN731ETTP1652B25 | 1 | G | PSRR17 |  |  |  |  |  |  |
|  |  |  |  | 57 | 57 | 61100YB00-044-G |  | RES,2.94KOhm,+/-0.1%,1/16W,G,SMD0402 | TA-I TECHNOLOGY CO., LTD | RB04BTP2941 | 1 | G | PSRR19 |  |  |  |  |  |  |
|  |  |  |  | 58 | 58 | 32013PD00-238-G |  | IC,Regulator,IR3883MTRPbF,ADJ,3A,G,QFN-16,SMD | INTERNATIONAL RECTIFIER | IR3883MTRPBF | 1 | G | PSRU1 |  |  |  |  |  |  |
|  |  |  |  | 59 | 59 | 510504M00-237-G |  | MOS N/N,BSS138DW-7-F,50V,0.2A,3.5ohm@10V,G,SOT363-6,SMD | DIODES INEORPORATION | BSS138DW-7-F | 25 | G | QN19,QN20,QN25,QN26,QN27,QN28,QN29,QN30,QN31,QN33,QN34,QN35,QN36,QN37,QN38,QN39,QN40,QN41,QN42,QN43,QN44,QN45,QN46,QN47,QN48 |  |  |  |  |  |  |
|  |  |  |  | 60 | 60 | 61011H500-017-G | - | RES,22 Ohm,+/-1%,1/16W,G,SMD0402 | KOA SPEER ELECTRONICS, INC. | RK73H1ETTP22R0F | 12 | G | R1,R14,R338,R504,R509,R531,R550,R552,R572,R868,R869,R2148 |  |  |  |  |  |  |
|  |  |  |  |  | 60 | 61011H500-012-G |  | RES,22 Ohm,+/-1%,1/16W,G,SMD0402 | WALSIN TECHNOLOGY CORPORATION | WR04X22R0FTL |  | G |  |  |  |  |  |  |  |
|  |  |  |  |  | 60 | 61011H500-011-G |  | RES,22 Ohm,+/-1%,1/16W,G,SMD0402 | YAGEO CORPORATION COMPONENT | RC0402FR-0722RL |  | G |  |  |  |  |  |  |  |
|  |  |  |  |  | 60 | 61011H500-044-G |  | RES,22 Ohm,+/-1%,1/16W,G,SMD0402 | TA-I TECHNOLOGY CO., LTD | RM04FTN22R0 |  | G |  |  |  |  |  |  |  |
|  |  |  |  |  | 60 | 61011H500-024-G |  | RES,22 Ohm,+/-1%,1/16W,G,SMD0402 | PANASONIC INDUSTRIAL CO.,LTD. | ERJ2RKF22R0X |  | G |  |  |  |  |  |  |  |
|  |  |  |  | 61 | 61 | 61011MQ00-017-G | - | RES,4.75KOhm,+/-1%,1/16W,G,SMD0402 | KOA SPEER ELECTRONICS, INC. | RK73H1ETTP4751F | 2 | G | R2,R4 |  |  |  |  |  |  |
|  |  |  |  |  | 61 | 61011MQ00-011-G |  | RES,4.75KOhm,+/-1%,1/16W,G,SMD0402 | YAGEO CORPORATION COMPONENT | RC0402FR-074K75L |  | G |  |  |  |  |  |  |  |
|  |  |  |  |  | 61 | 61011MQ00-012-G |  | RES,4.75KOhm,+/-1%,1/16W,G,SMD0402 | WALSIN TECHNOLOGY CORPORATION | WR04X4751FTL |  | G |  |  |  |  |  |  |  |
|  |  |  |  |  | 61 | 61011MQ00-044-G |  | RES,4.75KOhm,+/-1%,1/16W,G,SMD0402 | TA-I TECHNOLOGY CO., LTD | RM04FTN4751 |  | G |  |  |  |  |  |  |  |
|  |  |  |  | 62 | 62 | 610107B00-017-G | K9576 | RES,4.7KOhm,+/-5%,1/16W,G,SMD0402 | KOA SPEER ELECTRONICS, INC. | RK73B1ETTP472J | 134 | G | R6,R7,R9,R16,R17,R18,R62,R228,R312,R323,R324,R331,R333,R337,R411,R413,R417,R427,R429,R433,R443,R445,R448,R460,R461,R465,R475,R477,R480,R492,R493,R497,R503,R505,R506,R507,R510,R512,R513,R514,R516,R527,R528,R541,R546,R547,R548,R549,R553,R555,R556,R557,R559,R560,R617,R619,R622,R634,R635,R639,R649,R651,R654,R666,R667,R671,R681,R683,R686,R698,R699,R703,R713,R715,R718,R730,R731,R735,R745,R747,R750,R762,R763,R767,R777,R779,R782,R794,R795,R799,R809,R811,R814,R826,R827,R831,R841,R843,R846,R858,R859,R863,R866,R1078,R1079,R1603,R1668,R1681,R1684,R1688,R1694,R1697,R1783,R2128,R2129,R2130,R2131,R2132,R2133,R2134,R2135,R2136,R2137,R2138,R2139,R2140,R2141,R2142,R2143,R2144,R2145,R2146,R2147,R2149 |  |  |  |  |  |  |
|  |  |  |  |  | 62 | 610107B00-012-G |  | RES,4.7KOhm,+/-5%,1/16W,G,SMD0402 | WALSIN TECHNOLOGY CORPORATION | WR04X472JTL |  | G |  |  |  |  |  |  |  |
|  |  |  |  |  | 62 | 610107B00-011-G |  | RES,4.7KOhm,+/-5%,1/16W,G,SMD0402 | YAGEO CORPORATION COMPONENT | RC0402JR-074K7L |  | G |  |  |  |  |  |  |  |
|  |  |  |  |  | 62 | 610107B00-044-G |  | RES,4.7KOhm,+/-5%,1/16W,G,SMD0402 | TA-I TECHNOLOGY CO., LTD | RM04JTN472 |  | G |  |  |  |  |  |  |  |
|  |  |  |  |  | 62 | 610107B00-024-G |  | RES,4.7KOhm,+/-5%,1/16W,G,SMD0402 | PANASONIC INDUSTRIAL CO.,LTD. | ERJ2GEJ472X |  | G |  |  |  |  |  |  |  |
|  |  |  |  |  | 62 | 610107B00-029-G |  | RES,4.7KOhm,+/-5%,1/16W,G,SMD0402 | VISHAY ENTER TECHNO LOGY.INC | CRCW04024K70JNED |  | G |  |  |  |  |  |  |  |
|  |  |  |  | 63 | 63 | 61010JY00-017-G | - | RES,220 Ohm,+/-5%,1/16W,G,SMD0402 | KOA SPEER ELECTRONICS, INC. | RK73B1ETTP221J | 10 | G | R12,R15,R1672,R1673,R1679,R1683,R1687,R1698,R1780,R1782 |  |  |  |  |  |  |
|  |  |  |  |  | 63 | 61010JY00-012-G |  | RES,220 Ohm,+/-5%,1/16W,G,SMD0402 | WALSIN TECHNOLOGY CORPORATION | WR04X221JTL |  | G |  |  |  |  |  |  |  |
|  |  |  |  |  | 63 | 61010JY00-011-G |  | RES,220 Ohm,+/-5%,1/16W,G,SMD0402 | YAGEO CORPORATION COMPONENT | RC0402JR-07220RL |  | G |  |  |  |  |  |  |  |
|  |  |  |  |  | 63 | 61010JY00-044-G |  | RES,220 Ohm,+/-5%,1/16W,G,SMD0402 | TA-I TECHNOLOGY CO., LTD | RM04JTN221 |  | G |  |  |  |  |  |  |  |
|  |  |  |  | 64 | 64 | 610101V00-017-G | K9572 | RES,22 Ohm,+/-5%,1/16W,G,SMD0402 | KOA SPEER ELECTRONICS, INC. | RK73B1ETTP220J | 40 | G | R106,R1740,R1741,R1742,R1743,R1744,R1745,R1746,R1747,R1748,R1749,R1750,R1751,R1752,R1753,R1754,R1755,R1756,R1757,R1758,R1759,R1760,R1761,R1762,R1763,R1764,R1765,R1766,R1767,R1768,R1769,R1770,R1771,R1772,R1773,R1774,R1775,R1776,R1777,R1778 |  |  |  |  |  |  |
|  |  |  |  |  | 64 | 610101V00-012-G |  | RES,22 Ohm,+/-5%,1/16W,G,SMD0402 | WALSIN TECHNOLOGY CORPORATION | WR04X220JTL |  | G |  |  |  |  |  |  |  |
|  |  |  |  |  | 64 | 610101V00-011-G |  | RES,22 Ohm,+/-5%,1/16W,G,SMD0402 | YAGEO CORPORATION COMPONENT | RC0402JR-0722RL |  | G |  |  |  |  |  |  |  |
|  |  |  |  |  | 64 | 610101V00-044-G |  | RES,22 Ohm,+/-5%,1/16W,G,SMD0402 | TA-I TECHNOLOGY CO., LTD | RM04JTN220 |  | G |  |  |  |  |  |  |  |
|  |  |  |  |  | 64 | 610101V00-024-G |  | RES,22 Ohm,+/-5%,1/16W,G,SMD0402 | PANASONIC INDUSTRIAL CO.,LTD. | ERJ2GEJ220X |  | G |  |  |  |  |  |  |  |
|  |  |  |  | 65 | 65 | 610118100-017-G | - | RES,1.4KOhm,+/-1%,1/16W,G,SMD0402 | KOA SPEER ELECTRONICS, INC. | RK73H1ETTP1401F | 2 | G | R251,R252 |  |  |  |  |  |  |
|  |  |  |  |  | 65 | 610118100-012-G |  | RES,1.4KOhm,+/-1%,1/16W,G,SMD0402 | WALSIN TECHNOLOGY CORPORATION | WR04X1401FTL |  | G |  |  |  |  |  |  |  |
|  |  |  |  |  | 65 | 610118100-011-G |  | RES,1.4KOhm,+/-1%,1/16W,G,SMD0402 | YAGEO CORPORATION COMPONENT | RC0402FR-071K4L |  | G |  |  |  |  |  |  |  |
|  |  |  |  |  | 65 | 610118100-044-G |  | RES,1.4KOhm,+/-1%,1/16W,G,SMD0402 | TA-I TECHNOLOGY CO., LTD | RM04FTN1401 |  | G |  |  |  |  |  |  |  |
|  |  |  |  |  | 65 | 610118100-024-G |  | RES,1.4KOhm,+/-1%,1/16W,G,SMD0402 | PANASONIC INDUSTRIAL CO.,LTD. | ERJ2RKF1401X |  | G |  |  |  |  |  |  |  |
|  |  |  |  | 66 | 66 | 61010BG00-017-G | RJ328 | RES,100 Ohm,+/-1%,1/10W,G,SMD0603 | KOA SPEER ELECTRONICS, INC. | RK73H1JTTD1000F | 72 | G | R313,R317,R319,R330,R332,R335,R410,R412,R415,R426,R428,R431,R442,R444,R447,R458,R459,R463,R474,R476,R479,R490,R491,R495,R616,R618,R621,R632,R633,R637,R648,R650,R653,R664,R665,R669,R680,R682,R685,R696,R697,R701,R712,R714,R717,R728,R729,R733,R744,R746,R749,R760,R761,R765,R776,R778,R781,R792,R793,R797,R808,R810,R813,R824,R825,R829,R840,R842,R845,R856,R857,R861 |  |  |  |  |  |  |
|  |  |  |  |  | 66 | 61010BG00-012-G |  | RES,100 Ohm,+/-1%,1/10W,G,SMD0603 | WALSIN TECHNOLOGY CORPORATION | WR06X1000FTL |  | G |  |  |  |  |  |  |  |
|  |  |  |  |  | 66 | 61010BG00-011-G |  | RES,100 Ohm,+/-1%,1/10W,G,SMD0603 | YAGEO CORPORATION COMPONENT | RC0603FR-07100RL |  | G |  |  |  |  |  |  |  |
|  |  |  |  | 67 | 67 | 61011QA00-017-G | - | RES,24KOhm,+/-5%,1/16W,G,SMD0402 | KOA SPEER ELECTRONICS, INC. | RK73B1ETTP243J | 24 | G | R314,R327,R407,R423,R439,R454,R471,R486,R613,R628,R645,R660,R677,R692,R709,R724,R741,R756,R773,R788,R805,R820,R837,R852 |  |  |  |  |  |  |
|  |  |  |  |  | 67 | 61011QA00-011-G |  | RES,24KOhm,+/-5%,1/16W,G,SMD0402 | YAGEO CORPORATION COMPONENT | RC0402JR-0724KL |  | G |  |  |  |  |  |  |  |
|  |  |  |  |  | 67 | 61011QA00-012-G |  | RES,24KOhm,+/-5%,1/16W,G,SMD0402 | WALSIN TECHNOLOGY CORPORATION | WR04X243JTL |  | G |  |  |  |  |  |  |  |
|  |  |  |  |  | 67 | 61011QA00-044-G |  | RES,24KOhm,+/-5%,1/16W,G,SMD0402 | TA-I TECHNOLOGY CO., LTD | RM04JTN243 |  | G |  |  |  |  |  |  |  |
|  |  |  |  | 68 | 68 | 610115Y00-017-G | - | RES,16.2KOhm,+/-1%,1/16W,G,SMD0402 | KOA SPEER ELECTRONICS, INC. | RK73H1ETTP1622F | 24 | G | R318,R326,R406,R422,R438,R455,R470,R487,R612,R629,R644,R661,R676,R693,R708,R725,R740,R757,R772,R789,R804,R821,R836,R853 |  |  |  |  |  |  |
|  |  |  |  |  | 68 | 610115Y00-011-G |  | RES,16.2KOhm,+/-1%,1/16W,G,SMD0402 | YAGEO CORPORATION COMPONENT | RC0402FR-0716K2L |  | G |  |  |  |  |  |  |  |
|  |  |  |  |  | 68 | 610115Y00-012-G |  | RES,16.2KOhm,+/-1%,1/16W,G,SMD0402 | WALSIN TECHNOLOGY CORPORATION | WR04X1622FTL |  | G |  |  |  |  |  |  |  |
|  |  |  |  |  | 68 | 610115Y00-044-G |  | RES,16.2KOhm,+/-1%,1/16W,G,SMD0402 | TA-I TECHNOLOGY CO., LTD | RM04FTN1622 |  | G |  |  |  |  |  |  |  |
|  |  |  |  |  | 68 | 610115Y00-024-G |  | RES,16.2KOhm,+/-1%,1/16W,G,SMD0402 | PANASONIC INDUSTRIAL CO.,LTD. | ERJ2RKF1622X |  | G |  |  |  |  |  |  |  |
|  |  |  |  |  | 68 | 610115Y00-029-G |  | RES,16.2KOhm,+/-1%,1/16W,G,SMD0402 | VISHAY ENTER TECHNO LOGY.INC | CRCW040216K2FKED |  | G |  |  |  |  |  |  |  |
|  |  |  |  | 69 | 69 | 61100LQ00-017-G |  | RES,20KOhm,+/-1%,1/16W,G,SMD0402 | KOA SPEER ELECTRONICS, INC. | RN731ETTP2002F50 | 44 | G | R348,R1522,R1523,R1524,R1525,R1526,R1527,R1528,R1529,R1530,R1531,R1532,R1533,R1534,R1535,R1536,R1537,R1538,R1539,R1540,R1541,R1542,R1543,R1544,R1545,R1546,R1547,R1548,R1549,R1550,R1551,R1552,R1553,R1554,R1555,R1556,R1557,R1558,R1559,R1560,R1561,R1563,R1565,R1567 |  |  |  |  |  |  |
|  |  |  |  |  | 69 | 61100LQ00-011-G |  | RES,20KOhm,+/-1%,1/16W,G,SMD0402 | YAGEO CORPORATION COMPONENT | RT0402FRE0720KL |  | G |  |  |  |  |  |  |  |
|  |  |  |  |  | 69 | 61100LQ00-044-G |  | RES,20KOhm,+/-1%,1/16W,G,SMD0402 | TA-I TECHNOLOGY CO., LTD | RB04FTS2002 |  | G |  |  |  |  |  |  |  |
|  |  |  |  |  | 69 | 61100LQ00-012-G |  | RES,20KOhm,+/-1%,1/16W,G,SMD0402 | WALSIN TECHNOLOGY CORPORATION | WF04T2002FTL |  | G |  |  |  |  |  |  |  |
|  |  |  |  | 70 | 70 | 610114J00-017-G | - | RES,2KOhm,+/-1%,1/16W,G,SMD0402 | KOA SPEER ELECTRONICS, INC. | RK73H1ETTP2001F | 5 | G | R501,R502,R508,R544,R545 |  |  |  |  |  |  |
|  |  |  |  |  | 70 | 610114J00-012-G |  | RES,2KOhm,+/-1%,1/16W,G,SMD0402 | WALSIN TECHNOLOGY CORPORATION | WR04X2001FTL |  | G |  |  |  |  |  |  |  |
|  |  |  |  |  | 70 | 610114J00-011-G |  | RES,2KOhm,+/-1%,1/16W,G,SMD0402 | YAGEO CORPORATION COMPONENT | RC0402FR-072KL |  | G |  |  |  |  |  |  |  |
|  |  |  |  |  | 70 | 610114J00-044-G |  | RES,2KOhm,+/-1%,1/16W,G,SMD0402 | TA-I TECHNOLOGY CO., LTD | RM04FTN2001 |  | G |  |  |  |  |  |  |  |
|  |  |  |  |  | 70 | 610114J00-024-G |  | RES,2KOhm,+/-1%,1/16W,G,SMD0402 | PANASONIC INDUSTRIAL CO.,LTD. | ERJ2RKF2001X |  | G |  |  |  |  |  |  |  |
|  |  |  |  |  | 70 | 610114J00-029-G |  | RES,2KOhm,+/-1%,1/16W,G,SMD0402 | VISHAY ENTER TECHNO LOGY.INC | CRCW04022K00FKED |  | G |  |  |  |  |  |  |  |
|  |  |  |  | 71 | 71 | 610100T00-017-G |  | RES,1KOhm,+/-5%,1/16W,G,SMD0402 | KOA SPEER ELECTRONICS, INC. | RK73B1ETTP102J | 41 | G | R515,R517,R518,R519,R521,R522,R523,R524,R558,R561,R562,R564,R565,R566,R567,R1314,R1786,R1789,R1790,R1792,R1794,R1797,R1798,R1801,R1802,R1805,R1806,R1809,R1810,R1813,R1814,R1817,R1818,R1821,R1822,R1825,R1826,R1829,R1830,R2052,R2082 |  |  |  |  |  |  |
|  |  |  |  |  | 71 | 610100T00-012-G |  | RES,1KOhm,+/-5%,1/16W,G,SMD0402 | WALSIN TECHNOLOGY CORPORATION | WR04X102JTL |  | G |  |  |  |  |  |  |  |
|  |  |  |  |  | 71 | 610100T00-011-G |  | RES,1KOhm,+/-5%,1/16W,G,SMD0402 | YAGEO CORPORATION COMPONENT | RC0402JR-071KL |  | G |  |  |  |  |  |  |  |
|  |  |  |  |  | 71 | 610100T00-044-G |  | RES,1KOhm,+/-5%,1/16W,G,SMD0402 | TA-I TECHNOLOGY CO., LTD | RM04JTN102 |  | G |  |  |  |  |  |  |  |
|  |  |  |  |  | 71 | 610100T00-024-G |  | RES,1KOhm,+/-5%,1/16W,G,SMD0402 | PANASONIC INDUSTRIAL CO.,LTD. | ERJ2GEJ102X |  | G |  |  |  |  |  |  |  |
|  |  |  |  | 72 | 72 | 61010L300-017-G | - | RES,1KOhm,+/-1%,1/16W,G,SMD0402 | KOA SPEER ELECTRONICS, INC. | RK73H1ETTP1001F | 10 | G | R525,R532,R865,R1072,R1073,R1074,R1077,R1438,R1439,R1440 |  |  |  |  |  |  |
|  |  |  |  |  | 72 | 61010L300-012-G |  | RES,1KOhm,+/-1%,1/16W,G,SMD0402 | WALSIN TECHNOLOGY CORPORATION | WR04X1001FTL |  | G |  |  |  |  |  |  |  |
|  |  |  |  |  | 72 | 61010L300-011-G |  | RES,1KOhm,+/-1%,1/16W,G,SMD0402 | YAGEO CORPORATION COMPONENT | RC0402FR-071KL |  | G |  |  |  |  |  |  |  |
|  |  |  |  |  | 72 | 61010L300-044-G |  | RES,1KOhm,+/-1%,1/16W,G,SMD0402 | TA-I TECHNOLOGY CO., LTD | RM04FTN1001 |  | G |  |  |  |  |  |  |  |
|  |  |  |  |  | 72 | 61010L300-024-G |  | RES,1KOhm,+/-1%,1/16W,G,SMD0402 | PANASONIC INDUSTRIAL CO.,LTD. | ERJ2RKF1001X |  | G |  |  |  |  |  |  |  |
|  |  |  |  |  | 72 | 61010L300-029-G |  | RES,1KOhm,+/-1%,1/16W,G,SMD0402 | VISHAY ENTER TECHNO LOGY.INC | CRCW04021K00FKED |  | G |  |  |  |  |  |  |  |
|  |  |  |  | 73 | 73 | 61010PS00-017-G | - | RES,200KOhm,+/-1%,1/16W,G,SMD0402 | KOA SPEER ELECTRONICS, INC. | RK73H1ETTP2003F | 2 | G | R526,R533 |  |  |  |  |  |  |
|  |  |  |  |  | 73 | 61010PS00-012-G |  | RES,200KOhm,+/-1%,1/16W,G,SMD0402 | WALSIN TECHNOLOGY CORPORATION | WR04X2003FTL |  | G |  |  |  |  |  |  |  |
|  |  |  |  |  | 73 | 61010PS00-011-G |  | RES,200KOhm,+/-1%,1/16W,G,SMD0402 | YAGEO CORPORATION COMPONENT | RC0402FR-07200KL |  | G |  |  |  |  |  |  |  |
|  |  |  |  |  | 73 | 61010PS00-044-G |  | RES,200KOhm,+/-1%,1/16W,G,SMD0402 | TA-I TECHNOLOGY CO., LTD | RM04FTN2003 |  | G |  |  |  |  |  |  |  |
|  |  |  |  | 74 | 74 | 61011BW00-017-G |  | RES,1.2KOhm,+/-1%,1/16W,G,SMD0402 | KOA SPEER ELECTRONICS, INC. | RK73H1ETTP1201F | 2 | G | R529,R535 |  |  |  |  |  |  |
|  |  |  |  |  | 74 | 61011BW00-012-G |  | RES,1.2KOhm,+/-1%,1/16W,G,SMD0402 | WALSIN TECHNOLOGY CORPORATION | WR04X1201FTL |  | G |  |  |  |  |  |  |  |
|  |  |  |  |  | 74 | 61011BW00-011-G |  | RES,1.2KOhm,+/-1%,1/16W,G,SMD0402 | YAGEO CORPORATION COMPONENT | RC0402FR-071K2L |  | G |  |  |  |  |  |  |  |
|  |  |  |  |  | 74 | 61011BW00-044-G |  | RES,1.2KOhm,+/-1%,1/16W,G,SMD0402 | TA-I TECHNOLOGY CO., LTD | RM04FTN1201 |  | G |  |  |  |  |  |  |  |
|  |  |  |  | 75 | 75 | 610116V00-017-G | - | RES,232KOhm,+/-1%,1/16W,G,SMD0402 | KOA SPEER ELECTRONICS, INC. | RK73H1ETTP2323F | 1 | G | R530 |  |  |  |  |  |  |
|  |  |  |  |  | 75 | 610116V00-012-G |  | RES,232KOhm,+/-1%,1/16W,G,SMD0402 | WALSIN TECHNOLOGY CORPORATION | WR04X2323FTL |  | G |  |  |  |  |  |  |  |
|  |  |  |  |  | 75 | 610116V00-011-G |  | RES,232KOhm,+/-1%,1/16W,G,SMD0402 | YAGEO CORPORATION COMPONENT | RC0402FR-07232KL |  | G |  |  |  |  |  |  |  |
|  |  |  |  |  | 75 | 610116V00-044-G |  | RES,232KOhm,+/-1%,1/16W,G,SMD0402 | TA-I TECHNOLOGY CO., LTD | RM04FTN2323 |  | G |  |  |  |  |  |  |  |
|  |  |  |  | 76 | 76 | 610116B00-017-G |  | RES,180KOhm,+/-1%,1/16W,G,SMD0402 | KOA SPEER ELECTRONICS, INC. | RK73H1ETTP1803F | 1 | G | R534 |  |  |  |  |  |  |
|  |  |  |  |  | 76 | 610116B00-012-G |  | RES,180KOhm,+/-1%,1/16W,G,SMD0402 | WALSIN TECHNOLOGY CORPORATION | WR04X1803FTL |  | G |  |  |  |  |  |  |  |
|  |  |  |  |  | 76 | 610116B00-011-G |  | RES,180KOhm,+/-1%,1/16W,G,SMD0402 | YAGEO CORPORATION COMPONENT | RC0402FR-07180KL |  | G |  |  |  |  |  |  |  |
|  |  |  |  |  | 76 | 610116B00-044-G |  | RES,180KOhm,+/-1%,1/16W,G,SMD0402 | TA-I TECHNOLOGY CO., LTD | RM04FTN1803 |  | G |  |  |  |  |  |  |  |
|  |  |  |  | 77 | 77 | 61011BQ00-017-G | - | RES,2.2 Ohm,+/-5%,1/16W,G,SMD0402 | KOA SPEER ELECTRONICS, INC. | RK73B1ETTP2R2J | 2 | G | R540,R583 |  |  |  |  |  |  |
|  |  |  |  |  | 77 | 61011BQ00-011-G |  | RES,2.2 Ohm,+/-5%,1/16W,G,SMD0402 | YAGEO CORPORATION COMPONENT | RC0402JR-072R2L |  | G |  |  |  |  |  |  |  |
|  |  |  |  |  | 77 | 61011BQ00-012-G |  | RES,2.2 Ohm,+/-5%,1/16W,G,SMD0402 | WALSIN TECHNOLOGY CORPORATION | WR04X2R2JTL |  | G |  |  |  |  |  |  |  |
|  |  |  |  |  | 77 | 61011BQ00-044-G |  | RES,2.2 Ohm,+/-5%,1/16W,G,SMD0402 | TA-I TECHNOLOGY CO., LTD | RM04JTN2R2 |  | G |  |  |  |  |  |  |  |
|  |  |  |  | 78 | 78 | 610108300-017-G | - | RES,0 Ohm,+/-5%,1/10W,G,SMD0603 | KOA SPEER ELECTRONICS, INC. | RK73Z1JTTD | 2 | G | R542,R585 |  |  |  |  |  |  |
|  |  |  |  |  | 78 | 610108300-012-G |  | RES,0 Ohm,+/-5%,1/10W,G,SMD0603 | WALSIN TECHNOLOGY CORPORATION | WR06X000PTL |  | G |  |  |  |  |  |  |  |
|  |  |  |  |  | 78 | 610108300-011-G |  | RES,0 Ohm,+/-5%,1/10W,G,SMD0603 | YAGEO CORPORATION COMPONENT | RC0603JR-070RL |  | G |  |  |  |  |  |  |  |
|  |  |  |  |  | 78 | 610108300-044-G |  | RES,0 Ohm,+/-5%,1/10W,G,SMD0603 | TA-I TECHNOLOGY CO., LTD | RM06JTN0 |  | G |  |  |  |  |  |  |  |
|  |  |  |  |  | 78 | 610108300-024-G |  | RES,0 Ohm,+/-5%,1/10W,G,SMD0603 | PANASONIC INDUSTRIAL CO.,LTD. | ERJ3GEY0R00V |  | G |  |  |  |  |  |  |  |
|  |  |  |  | 79 | 79 | 61010FE00-017-G | - | RES,100 Ohm,+/-1%,1/16W,G,SMD0402 | KOA SPEER ELECTRONICS, INC. | RK73H1ETTP1000F | 1 | G | R543 |  |  |  |  |  |  |
|  |  |  |  |  | 79 | 61010FE00-012-G |  | RES,100 Ohm,+/-1%,1/16W,G,SMD0402 | WALSIN TECHNOLOGY CORPORATION | WR04X1000FTL |  | G |  |  |  |  |  |  |  |
|  |  |  |  |  | 79 | 61010FE00-011-G |  | RES,100 Ohm,+/-1%,1/16W,G,SMD0402 | YAGEO CORPORATION COMPONENT | RC0402FR-07100RL |  | G |  |  |  |  |  |  |  |
|  |  |  |  |  | 79 | 61010FE00-044-G |  | RES,100 Ohm,+/-1%,1/16W,G,SMD0402 | TA-I TECHNOLOGY CO., LTD | RM04FTN1000 |  | G |  |  |  |  |  |  |  |
|  |  |  |  | 80 | 80 | 610118400-017-G |  | RES,27 Ohm,+/-1%,1/16W,G,SMD0402 | KOA SPEER ELECTRONICS, INC. | RK73H1ETTP27R0F | 32 | G | R817,R818,R828,R830,R832,R833,R834,R860,R867,R1443,R1444,R1445,R1446,R1447,R1448,R1458,R1459,R1460,R1461,R1462,R1463,R1464,R1465,R1466,R1467,R1468,R1469,R1470,R1471,R1472,R1473,R1604 |  |  |  |  |  |  |
|  |  |  |  |  | 80 | 610118400-012-G |  | RES,27 Ohm,+/-1%,1/16W,G,SMD0402 | WALSIN TECHNOLOGY CORPORATION | WR04X27R0FTL |  | G |  |  |  |  |  |  |  |
|  |  |  |  |  | 80 | 610118400-011-G |  | RES,27 Ohm,+/-1%,1/16W,G,SMD0402 | YAGEO CORPORATION COMPONENT | RC0402FR-0727RL |  | G |  |  |  |  |  |  |  |
|  |  |  |  |  | 80 | 610118400-044-G |  | RES,27 Ohm,+/-1%,1/16W,G,SMD0402 | TA-I TECHNOLOGY CO., LTD | RM04FTN27R0 |  | G |  |  |  |  |  |  |  |
|  |  |  |  | 81 | 81 | 610113A00-017-G | - | RES,2.2 Ohm,+/-5%,1/2W,G,SMD1210 | KOA SPEER ELECTRONICS, INC. | RK73B2ETTD2R2J | 24 | G | R874,R876,R878,R880,R882,R884,R886,R888,R890,R892,R894,R896,R898,R900,R902,R904,R906,R908,R910,R912,R914,R916,R918,R920 |  |  |  |  |  |  |
|  |  |  |  |  | 81 | 610113A00-012-G |  | RES,2.2 Ohm,+/-5%,1/2W,G,SMD1210 | WALSIN TECHNOLOGY CORPORATION | WF10P2R2JTL |  | G |  |  |  |  |  |  |  |
|  |  |  |  |  | 81 | 610113A00-011-G |  | RES,2.2 Ohm,+/-5%,1/2W,G,SMD1210 | YAGEO CORPORATION COMPONENT | RC1210JR-072R2L |  | G |  |  |  |  |  |  |  |
|  |  |  |  | 82 | 82 | 61015K700-017-G |  | RES,3.3 Ohm,+/-5%,1/2W,G,SMD1210 | KOA SPEER ELECTRONICS, INC. | RK73B2ETTD3R3J | 24 | G | R875,R877,R879,R881,R883,R885,R887,R889,R891,R893,R895,R897,R899,R901,R903,R905,R907,R909,R911,R913,R915,R917,R919,R921 |  |  |  |  |  |  |
|  |  |  |  |  | 82 | 61015K700-011-G |  | RES,3.3 Ohm,+/-5%,1/2W,G,SMD1210 | YAGEO CORPORATION COMPONENT | RC1210JR-073R3L |  | G |  |  |  |  |  |  |  |
|  |  |  |  | 83 | 83 | 61011MV00-017-G |  | RES,510 Ohm,+/-1%,1/16W,G,SMD0402 | KOA SPEER ELECTRONICS, INC. | RK73H1ETTP5100F | 24 | G | R1313,R1785,R1787,R1788,R1791,R1793,R1795,R1796,R1799,R1800,R1803,R1804,R1807,R1808,R1811,R1812,R1815,R1816,R1819,R1820,R1823,R1824,R1827,R1828 |  |  |  |  |  |  |
|  |  |  |  |  | 83 | 61011MV00-012-G |  | RES,510 Ohm,+/-1%,1/16W,G,SMD0402 | WALSIN TECHNOLOGY CORPORATION | WR04X5100FTL |  | G |  |  |  |  |  |  |  |
|  |  |  |  |  | 83 | 61011MV00-011-G |  | RES,510 Ohm,+/-1%,1/16W,G,SMD0402 | YAGEO CORPORATION COMPONENT | RC0402FR-07510RL |  | G |  |  |  |  |  |  |  |
|  |  |  |  |  | 83 | 61011MV00-044-G |  | RES,510 Ohm,+/-1%,1/16W,G,SMD0402 | TA-I TECHNOLOGY CO., LTD | RM04FTN5100 |  | G |  |  |  |  |  |  |  |
|  |  |  |  | 84 | 84 | 610107L00-017-G |  | RES,1 Ohm,+/-5%,1/10W,G,SMD0603 | KOA SPEER ELECTRONICS, INC. | RK73B1JTTD1R0J | 2 | G | R1408,R1449 |  |  |  |  |  |  |
|  |  |  |  |  | 84 | 610107L00-011-G |  | RES,1 Ohm,+/-5%,1/10W,G,SMD0603 | YAGEO CORPORATION COMPONENT | RC0603JR-071RL |  | G |  |  |  |  |  |  |  |
|  |  |  |  |  | 84 | 610107L00-012-G |  | RES,1 Ohm,+/-5%,1/10W,G,SMD0603 | WALSIN TECHNOLOGY CORPORATION | WR06X1R0JTL |  | G |  |  |  |  |  |  |  |
|  |  |  |  |  | 84 | 610107L00-044-G |  | RES,1 Ohm,+/-5%,1/10W,G,SMD0603 | TA-I TECHNOLOGY CO., LTD | RM06JTN1R0 |  | G |  |  |  |  |  |  |  |
|  |  |  |  | 85 | 85 | 61100AH00-012-G |  | RES,10KOhm,+/-0.5%,1/16W,G,SMD0402 | WALSIN TECHNOLOGY CORPORATION | WF04U1002DTL | 12 | G | R2049,R2050,R2051,R2062,R2063,R2064,R2071,R2075,R2077,R2079,R2083,R2084 |  |  |  |  |  |  |
|  |  |  |  | 86 | 86 | 610154800-017-G |  | RES,1 Ohm,+/-5%,1/8W,G,SMD0402 | KOA SPEER ELECTRONICS, INC. | SG73P1ETTP1R0J | 1 | G | R2060 |  |  |  |  |  |  |
|  |  |  |  |  | 86 | 610154800-011-G |  | RES,1 Ohm,+/-5%,1/8W,G,SMD0402 | YAGEO CORPORATION COMPONENT | RC0402JR-7W1RL |  | G |  |  |  |  |  |  |  |
|  |  |  |  |  | 86 | 610154800-012-G |  | RES,1 Ohm,+/-5%,1/8W,G,SMD0402 | WALSIN TECHNOLOGY CORPORATION | WF04P1R0 JTL |  | G |  |  |  |  |  |  |  |
|  |  |  |  | 87 | 87 | 31010J400-131-G |  | IC,Gate&Inverter,TC7SZ08FU,1.8~5.5V,G,SSOP-5,SMD | TOSHIBA ELECTRONICS ASIA LTD | TC7SZ08FU | 3 | G | U_AND1,U_AND2,U5 |  |  |  |  |  |  |
|  |  |  |  | 88 | 88 | 41040J500-232-G |  | EEPROM,24AA024T-I/SN,1.7V~5.5V,2K,I2C,G,SOIC-8,SMD | MICROCHIP TECHNOLOGY INC | 24AA024T-I/SN | 1 | G | U_BP_FRU1 |  |  |  |  |  |  |
|  |  |  |  | 89 | 89 | 21050LL00-217-G | - | IC,IDT,9ZXL0831AKLFT,G,VFQFPN-48,SMD | INTEGRATED DEVICE TECHNOLOGY | 9ZXL0831AKLFT | 2 | G | U_Clock_B,U_Clock_A |  |  |  |  |  |  |
|  |  |  |  | 90 | 90 | 311004V00-223-G |  | Logic IC,Translator,PCA9617ADMR2G,Vcca=0.8V~5.5V,Vccb=2.2V~5.5V,102ns,Micro8,8P,G | ON SEMICONDUCTOR CORP | PCA9617ADMR2G | 2 | G | U_I2C_RE1,U_I2C_RE2 |  |  |  |  |  |  |
|  |  |  |  | 91 | 91 | 31030YF00-252-G |  | Logic IC,Switch,PI4MSD5V9546ALEX,1.65V~5.5V,0.3ns,TSSOP,16P,G | PERICOM SEMICONDUCTOR CORP | PI4MSD5V9546ALEX | 5 | G | U_MUX1,U_MUX2,U_MUX3,U_MUX4,U_MUX5 |  |  |  |  |  |  |
|  |  |  |  | 92 | 92 | 32040P400-399-G |  | IC,Voltage sensor,SLG4N020VTR,G,TDFN-8,SMD | SILEGO | SLG4N020VTR | 1 | G | U_RESET |  |  |  |  |  |  |
|  |  |  |  | 93 | 93 | 32022WB00-173-G |  | IC,Power Controller,MAX6420UK16+T,G,SOT-23-5P,SMD | MAXIM INTEGRATED PRODUCTS, INC. | MAX6420UK16+T | 1 | G | U_RESET1 |  |  |  |  |  |  |
|  |  |  |  | 94 | 94 | 21081NC00-432-G |  | IC,LSI,500021009,A2,G,TFBGA-141,SMD | LSI LOGIC CORPORATION | 500021009 | 2 | G | U_SF1,U_SF2 |  |  |  |  |  |  |
|  |  |  |  | 95 | 95 | 32040J800-183-G |  | IC,Temp Sensor,TMP75AIDGKR,N/A,G,MSOP-8,SMD | TEXAS INSTRUMENTS | TMP75AIDGKR | 1 | G | U_TMP1 |  |  |  |  |  |  |
|  |  |  |  | 96 | 96 | 310700500-183-G |  | IC,Decoder&Encoder,PCA9306DCUR,0~5V,G,VSSOP-8,SMD | TEXAS INSTRUMENTS | PCA9306DCUR | 2 | G | U1,U2 |  |  |  |  |  |  |
|  |  |  |  | 97 | 97 | 21050RJ00-217-G |  | IC,IDT,9FGL0651BKILFT,G,VFQFPN-40,SMD | INTEGRATED DEVICE TECHNOLOGY | 9FGL0651BKILFT | 1 | G | U29 |  |  |  |  |  |  |
|  |  |  |  | 98 | 98 | 310501200-183-G | - | IC,Buffer,SN74LVC1G07DCKR,1.65~5.5V,G,SC70-5,SMD | TEXAS INSTRUMENTS | SN74LVC1G07DCKR | 1 | G | U209 |  |  |  |  |  |  |
|  |  |  |  | 99 | 99 | 220106A00-413-G |  | IC,PLD,10M08SCU169C8G,3.3V,116MHz,G,BGA-169,SMD | ALTERA CORPORATION | 10M08SCU169C8G | 1 | G | U248 |  |  |  |  |  |  |
|  |  |  |  | 100 | 100 | 71012HD00-100-G |  | XTAL,25MHz,+/-20ppm,8pF,G,SMD | TXC CORPORATION | 7V25000054 | 1 | G | X7 |  |  |  |  |  |  |
|  |  |  |  | 101 | 101 | 2A5910Q00-HYM-G |  | SMT NUT,CARBON STEEL,G,FIVETECH,82-059-01-022-01-RL | Fivetech Technology Inc. | 82-059-01-022-01-RL | 10 | G | H1,H2,H3,H4,H7,H8,H9,H10,H30,H31 |  |  |  |  |  |  |
|  |  |  |  | 102 | 102 | 340718A00-245-G |  | CONN,SAS,V/T,0.6mm,30u,G,SMD-74 | AMPHENOL SHANGHAI CORP. | U10-B074-250T | 10 | G | JSAS1,JPCIE1,JSAS2,JPCIE2,JSAS3,JPCIE3,JPCIE4,JPCIE5,JPCIE6,JPCIE7 |  |  |  |  |  |  |
|  |  |  |  | 103 | 103 | 3406B6F00-317-G |  | CONN,Header,WTB,2X3,R/A,Bla,2.5mm,15u,G,SMD-6 | MOLEX INCORPORATED | 15-91-2065 | 1 | G | J_CPLD_JTAG |  |  |  |  |  |  |
|  |  |  |  | 104 | 104 | 340655900-245-G | - | CONN,Header,WTB,1X4,R/A,Whi,1mm,G,SMD-4 | AMPHENOL SHANGHAI CORP. | G846A04100Y1EU | 1 | G | J_LED1 |  |  |  |  |  |  |
|  |  |  |  | 105 | 105 | 340313H00-600-G | - | CONN,PCIE,V/T,Bla,0.8mm,30u,G,SMD-68 | FOXCONN TECHNOLOGY CO.,LTD. | LU25683-A001-9H | 24 | G | J_NVME01,J_NVME02,J_NVME03,J_NVME04,J_NVME05,J_NVME06,J_NVME07,J_NVME08,J_NVME09,J_NVME10,J_NVME11,J_NVME12,J_NVME13,J_NVME14,J_NVME15,J_NVME16,J_NVME17,J_NVME18,J_NVME19,J_NVME20,J_NVME21,J_NVME22,J_NVME23,J_NVME00 |  |  |  |  |  |  |
|  |  |  |  | 106 | 106 | 3406B3H00-317-G |  | CONN,Header,Power,2X8,V/T,Bla,3mm,G,SMD-16 | MOLEX INCORPORATED | 43045-1618 | 1 | G | J1 |  |  |  |  |  |  |
